(kicad_pcb
	(version 20260206)
	(generator "pcbnew")
	(generator_version "10.0")
	(general
		(thickness 1.6)
		(legacy_teardrops no)
	)
	(paper "A4")
	(title_block
		(title "01162023_DA0F0TEBIF0_F0T_Expander_BD_F_brd_V02_OCP.brd")
		(comment 1 "Grand Teton / footprints 1495-1501 of 9728")
	)
	(layers
		(0 "F.Cu" signal "TOP")
		(4 "In1.Cu" signal "GND")
		(6 "In2.Cu" signal "VCC")
		(8 "In3.Cu" signal "VCC1")
		(10 "In4.Cu" signal "GND1")
		(12 "In5.Cu" signal "IN1")
		(14 "In6.Cu" signal "GND2")
		(16 "In7.Cu" signal "IN2")
		(18 "In8.Cu" signal "GND3")
		(20 "In9.Cu" signal "IN3")
		(22 "In10.Cu" signal "GND4")
		(24 "In11.Cu" signal "IN4")
		(26 "In12.Cu" signal "GND5")
		(28 "In13.Cu" signal "IN5")
		(30 "In14.Cu" signal "GND6")
		(32 "In15.Cu" signal "IN6")
		(34 "In16.Cu" signal "GND7")
		(2 "B.Cu" signal "BOTTOM")
		(9 "F.Adhes" user "F.Adhesive")
		(11 "B.Adhes" user "B.Adhesive")
		(13 "F.Paste" user "Package Geometry/Pastemask Top")
		(15 "B.Paste" user "Package Geometry/Pastemask Bottom")
		(5 "F.SilkS" user "Ref Des/Silkscreen Top")
		(7 "B.SilkS" user "Ref Des/Silkscreen Bottom")
		(1 "F.Mask" user "Board Geometry/Soldermask Top")
		(3 "B.Mask" user "Board Geometry/Soldermask Bottom")
		(17 "Dwgs.User" user "User.Drawings")
		(19 "Cmts.User" user "User.Comments")
		(21 "Eco1.User" user "User.Eco1")
		(23 "Eco2.User" user "User.Eco2")
		(25 "Edge.Cuts" user "Board Geometry/Outline")
		(27 "Margin" user)
		(31 "F.CrtYd" user "Package Geometry/Place Bound Top")
		(29 "B.CrtYd" user "Package Geometry/Place Bound Bottom")
		(35 "F.Fab" user "Ref Des/Assembly Top")
		(33 "B.Fab" user "Ref Des/Assembly Bottom")
	)
	(footprint ""
		(layer "F.Cu")
		(at 366.07496 -303.649634 90)
		(property "Reference" "PC198"
			(at 0 0 90)
			(layer "F.SilkS")
			(hide yes)
			(effects
				(font
					(size 1.27 1.27)
				)
			)
		)
		(property "Value" ""
			(at 0 0 90)
			(layer "F.Fab")
			(effects
				(font
					(size 1.27 1.27)
				)
			)
		)
		(duplicate_pad_numbers_are_jumpers no)
		(fp_line
			(start 1.524 -0.762)
			(end 1.524 0.762)
			(stroke
				(width 0.1524)
				(type default)
			)
			(layer "F.SilkS")
		)
		(fp_line
			(start -1.524 -0.762)
			(end 1.524 -0.762)
			(stroke
				(width 0.1524)
				(type default)
			)
			(layer "F.SilkS")
		)
		(fp_line
			(start 1.524 0.762)
			(end -1.524 0.762)
			(stroke
				(width 0.1524)
				(type default)
			)
			(layer "F.SilkS")
		)
		(fp_line
			(start -1.524 0.762)
			(end -1.524 -0.762)
			(stroke
				(width 0.1524)
				(type default)
			)
			(layer "F.SilkS")
		)
		(fp_line
			(start 1.1049 -0.724916)
			(end -1.1049 -0.724916)
			(stroke
				(width 0.1)
				(type default)
			)
			(layer "F.Fab")
		)
		(fp_line
			(start -1.1049 -0.724916)
			(end -1.1049 0.724916)
			(stroke
				(width 0.1)
				(type default)
			)
			(layer "F.Fab")
		)
		(fp_line
			(start 1.1049 0.724916)
			(end 1.1049 -0.724916)
			(stroke
				(width 0.1)
				(type default)
			)
			(layer "F.Fab")
		)
		(fp_line
			(start -1.1049 0.724916)
			(end 1.1049 0.724916)
			(stroke
				(width 0.1)
				(type default)
			)
			(layer "F.Fab")
		)
		(pad "1" smd rect
			(at -0.889 0 270)
			(size 1.016 1.27)
			(layers "F.Cu" "F.Mask" "F.Paste")
			(net "P0V8_PEX3")
		)
		(pad "2" smd rect
			(at 0.889 0 270)
			(size 1.016 1.27)
			(layers "F.Cu" "F.Mask" "F.Paste")
			(net "GND")
		)
	)
	(footprint ""
		(layer "F.Cu")
		(at 58.175398 -379.567694)
		(property "Reference" "C4037"
			(at 0 0 0)
			(layer "F.SilkS")
			(hide yes)
			(effects
				(font
					(size 1.27 1.27)
				)
			)
		)
		(property "Value" ""
			(at 0 0 0)
			(layer "F.Fab")
			(effects
				(font
					(size 1.27 1.27)
				)
			)
		)
		(duplicate_pad_numbers_are_jumpers no)
		(fp_line
			(start -0.7874 -0.4064)
			(end 0.7874 -0.4064)
			(stroke
				(width 0.1524)
				(type default)
			)
			(layer "F.SilkS")
		)
		(fp_line
			(start -0.7874 0.4064)
			(end -0.7874 -0.4064)
			(stroke
				(width 0.1524)
				(type default)
			)
			(layer "F.SilkS")
		)
		(fp_line
			(start 0.7874 -0.4064)
			(end 0.7874 0.4064)
			(stroke
				(width 0.1524)
				(type default)
			)
			(layer "F.SilkS")
		)
		(fp_line
			(start 0.7874 0.4064)
			(end -0.7874 0.4064)
			(stroke
				(width 0.1524)
				(type default)
			)
			(layer "F.SilkS")
		)
		(fp_line
			(start -0.67945 -0.305054)
			(end -0.12065 -0.305054)
			(stroke
				(width 0.1)
				(type default)
			)
			(layer "F.Fab")
		)
		(fp_line
			(start -0.67945 0.3048)
			(end -0.67945 -0.305054)
			(stroke
				(width 0.1)
				(type default)
			)
			(layer "F.Fab")
		)
		(fp_line
			(start -0.12065 -0.305054)
			(end -0.12065 -0.2794)
			(stroke
				(width 0.1)
				(type default)
			)
			(layer "F.Fab")
		)
		(fp_line
			(start -0.12065 -0.2794)
			(end 0.12065 -0.2794)
			(stroke
				(width 0.1)
				(type default)
			)
			(layer "F.Fab")
		)
		(fp_line
			(start -0.12065 0.2794)
			(end -0.12065 0.3048)
			(stroke
				(width 0.1)
				(type default)
			)
			(layer "F.Fab")
		)
		(fp_line
			(start -0.12065 0.3048)
			(end -0.67945 0.3048)
			(stroke
				(width 0.1)
				(type default)
			)
			(layer "F.Fab")
		)
		(fp_line
			(start 0.120396 0.2794)
			(end -0.12065 0.2794)
			(stroke
				(width 0.1)
				(type default)
			)
			(layer "F.Fab")
		)
		(fp_line
			(start 0.120396 0.3048)
			(end 0.120396 0.2794)
			(stroke
				(width 0.1)
				(type default)
			)
			(layer "F.Fab")
		)
		(fp_line
			(start 0.12065 -0.3048)
			(end 0.67945 -0.3048)
			(stroke
				(width 0.1)
				(type default)
			)
			(layer "F.Fab")
		)
		(fp_line
			(start 0.12065 -0.2794)
			(end 0.12065 -0.3048)
			(stroke
				(width 0.1)
				(type default)
			)
			(layer "F.Fab")
		)
		(fp_line
			(start 0.67945 -0.3048)
			(end 0.67945 0.3048)
			(stroke
				(width 0.1)
				(type default)
			)
			(layer "F.Fab")
		)
		(fp_line
			(start 0.67945 0.3048)
			(end 0.120396 0.3048)
			(stroke
				(width 0.1)
				(type default)
			)
			(layer "F.Fab")
		)
		(pad "1" smd circle
			(at -0.40005 0)
			(size 0 0)
			(layers "F.Cu" "F.Mask" "F.Paste")
			(net "GND")
		)
		(pad "2" smd circle
			(at 0.40005 0)
			(size 0 0)
			(layers "F.Cu" "F.Mask" "F.Paste")
			(net "GPU_BASE_ID1")
		)
	)
	(footprint ""
		(layer "F.Cu")
		(at 146.815302 -59.546236 90)
		(property "Reference" "C2888"
			(at 0 0 90)
			(layer "F.SilkS")
			(hide yes)
			(effects
				(font
					(size 1.27 1.27)
				)
			)
		)
		(property "Value" ""
			(at 0 0 90)
			(layer "F.Fab")
			(effects
				(font
					(size 1.27 1.27)
				)
			)
		)
		(duplicate_pad_numbers_are_jumpers no)
		(fp_line
			(start 0.7874 -0.4064)
			(end 0.7874 0.4064)
			(stroke
				(width 0.1524)
				(type default)
			)
			(layer "F.SilkS")
		)
		(fp_line
			(start -0.7874 -0.4064)
			(end 0.7874 -0.4064)
			(stroke
				(width 0.1524)
				(type default)
			)
			(layer "F.SilkS")
		)
		(fp_line
			(start 0.7874 0.4064)
			(end -0.7874 0.4064)
			(stroke
				(width 0.1524)
				(type default)
			)
			(layer "F.SilkS")
		)
		(fp_line
			(start -0.7874 0.4064)
			(end -0.7874 -0.4064)
			(stroke
				(width 0.1524)
				(type default)
			)
			(layer "F.SilkS")
		)
		(fp_line
			(start -0.12065 -0.305054)
			(end -0.12065 -0.2794)
			(stroke
				(width 0.1)
				(type default)
			)
			(layer "F.Fab")
		)
		(fp_line
			(start -0.67945 -0.305054)
			(end -0.12065 -0.305054)
			(stroke
				(width 0.1)
				(type default)
			)
			(layer "F.Fab")
		)
		(fp_line
			(start 0.67945 -0.3048)
			(end 0.67945 0.3048)
			(stroke
				(width 0.1)
				(type default)
			)
			(layer "F.Fab")
		)
		(fp_line
			(start 0.12065 -0.3048)
			(end 0.67945 -0.3048)
			(stroke
				(width 0.1)
				(type default)
			)
			(layer "F.Fab")
		)
		(fp_line
			(start 0.12065 -0.2794)
			(end 0.12065 -0.3048)
			(stroke
				(width 0.1)
				(type default)
			)
			(layer "F.Fab")
		)
		(fp_line
			(start -0.12065 -0.2794)
			(end 0.12065 -0.2794)
			(stroke
				(width 0.1)
				(type default)
			)
			(layer "F.Fab")
		)
		(fp_line
			(start 0.120396 0.2794)
			(end -0.12065 0.2794)
			(stroke
				(width 0.1)
				(type default)
			)
			(layer "F.Fab")
		)
		(fp_line
			(start -0.12065 0.2794)
			(end -0.12065 0.3048)
			(stroke
				(width 0.1)
				(type default)
			)
			(layer "F.Fab")
		)
		(fp_line
			(start 0.67945 0.3048)
			(end 0.120396 0.3048)
			(stroke
				(width 0.1)
				(type default)
			)
			(layer "F.Fab")
		)
		(fp_line
			(start 0.120396 0.3048)
			(end 0.120396 0.2794)
			(stroke
				(width 0.1)
				(type default)
			)
			(layer "F.Fab")
		)
		(fp_line
			(start -0.12065 0.3048)
			(end -0.67945 0.3048)
			(stroke
				(width 0.1)
				(type default)
			)
			(layer "F.Fab")
		)
		(fp_line
			(start -0.67945 0.3048)
			(end -0.67945 -0.305054)
			(stroke
				(width 0.1)
				(type default)
			)
			(layer "F.Fab")
		)
		(pad "1" smd circle
			(at -0.40005 0 90)
			(size 0 0)
			(layers "F.Cu" "F.Mask" "F.Paste")
			(net "SSD5_AUX_P3V3_EN_R")
		)
		(pad "2" smd circle
			(at 0.40005 0 90)
			(size 0 0)
			(layers "F.Cu" "F.Mask" "F.Paste")
			(net "GND")
		)
	)
	(footprint ""
		(layer "F.Cu")
		(at 394.425424 -42.849038 180)
		(property "Reference" "R656"
			(at 0 0 180)
			(layer "F.SilkS")
			(hide yes)
			(effects
				(font
					(size 1.27 1.27)
				)
			)
		)
		(property "Value" ""
			(at 0 0 180)
			(layer "F.Fab")
			(effects
				(font
					(size 1.27 1.27)
				)
			)
		)
		(duplicate_pad_numbers_are_jumpers no)
		(fp_line
			(start 0.7874 0.4064)
			(end -0.7874 0.4064)
			(stroke
				(width 0.1524)
				(type default)
			)
			(layer "F.SilkS")
		)
		(fp_line
			(start 0.7874 -0.4064)
			(end 0.7874 0.4064)
			(stroke
				(width 0.1524)
				(type default)
			)
			(layer "F.SilkS")
		)
		(fp_line
			(start -0.7874 0.4064)
			(end -0.7874 -0.4064)
			(stroke
				(width 0.1524)
				(type default)
			)
			(layer "F.SilkS")
		)
		(fp_line
			(start -0.7874 -0.4064)
			(end 0.7874 -0.4064)
			(stroke
				(width 0.1524)
				(type default)
			)
			(layer "F.SilkS")
		)
		(fp_line
			(start 0.67945 0.3048)
			(end 0.120396 0.3048)
			(stroke
				(width 0.1)
				(type default)
			)
			(layer "F.Fab")
		)
		(fp_line
			(start 0.67945 -0.3048)
			(end 0.67945 0.3048)
			(stroke
				(width 0.1)
				(type default)
			)
			(layer "F.Fab")
		)
		(fp_line
			(start 0.12065 -0.2794)
			(end 0.12065 -0.3048)
			(stroke
				(width 0.1)
				(type default)
			)
			(layer "F.Fab")
		)
		(fp_line
			(start 0.12065 -0.3048)
			(end 0.67945 -0.3048)
			(stroke
				(width 0.1)
				(type default)
			)
			(layer "F.Fab")
		)
		(fp_line
			(start 0.120396 0.3048)
			(end 0.120396 0.2794)
			(stroke
				(width 0.1)
				(type default)
			)
			(layer "F.Fab")
		)
		(fp_line
			(start 0.120396 0.2794)
			(end -0.12065 0.2794)
			(stroke
				(width 0.1)
				(type default)
			)
			(layer "F.Fab")
		)
		(fp_line
			(start -0.12065 0.3048)
			(end -0.67945 0.3048)
			(stroke
				(width 0.1)
				(type default)
			)
			(layer "F.Fab")
		)
		(fp_line
			(start -0.12065 0.2794)
			(end -0.12065 0.3048)
			(stroke
				(width 0.1)
				(type default)
			)
			(layer "F.Fab")
		)
		(fp_line
			(start -0.12065 -0.2794)
			(end 0.12065 -0.2794)
			(stroke
				(width 0.1)
				(type default)
			)
			(layer "F.Fab")
		)
		(fp_line
			(start -0.12065 -0.305054)
			(end -0.12065 -0.2794)
			(stroke
				(width 0.1)
				(type default)
			)
			(layer "F.Fab")
		)
		(fp_line
			(start -0.67945 0.3048)
			(end -0.67945 -0.305054)
			(stroke
				(width 0.1)
				(type default)
			)
			(layer "F.Fab")
		)
		(fp_line
			(start -0.67945 -0.305054)
			(end -0.12065 -0.305054)
			(stroke
				(width 0.1)
				(type default)
			)
			(layer "F.Fab")
		)
		(pad "1" smd circle
			(at -0.40005 0 180)
			(size 0 0)
			(layers "F.Cu" "F.Mask" "F.Paste")
			(net "P12V_SSD13_R")
		)
		(pad "2" smd circle
			(at 0.40005 0 180)
			(size 0 0)
			(layers "F.Cu" "F.Mask" "F.Paste")
			(net "P12V_SSD13_VIN_P")
		)
	)
	(footprint ""
		(layer "F.Cu")
		(at 446.875408 -69.47916 180)
		(property "Reference" "PU118"
			(at -1.943862 4.07924 90)
			(unlocked yes)
			(layer "F.SilkS")
			(effects
				(font
					(size 0.7874 0.5842)
					(thickness 0.1524)
				)
			)
		)
		(property "Value" ""
			(at 0 0 180)
			(layer "F.Fab")
			(effects
				(font
					(size 1.27 1.27)
				)
			)
		)
		(duplicate_pad_numbers_are_jumpers no)
		(fp_line
			(start 1.239774 1.495298)
			(end -1.239774 1.495298)
			(stroke
				(width 0.1524)
				(type default)
			)
			(layer "F.SilkS")
		)
		(fp_line
			(start 1.239774 -1.495298)
			(end 1.239774 1.495298)
			(stroke
				(width 0.1524)
				(type default)
			)
			(layer "F.SilkS")
		)
		(fp_line
			(start -1.239774 1.495298)
			(end -1.239774 -1.495298)
			(stroke
				(width 0.1524)
				(type default)
			)
			(layer "F.SilkS")
		)
		(fp_line
			(start -1.239774 -1.495298)
			(end 1.239774 -1.495298)
			(stroke
				(width 0.1524)
				(type default)
			)
			(layer "F.SilkS")
		)
		(fp_poly
			(pts
				(xy -1.739392 -1.187958) (xy -2.457704 -0.469392) (xy -1.380236 -0.110236)
			)
			(stroke
				(width 0)
				(type default)
			)
			(fill yes)
			(layer "F.SilkS")
		)
		(fp_line
			(start 0.8001 1.050036)
			(end -0.8001 1.050036)
			(stroke
				(width 0.1)
				(type default)
			)
			(layer "F.Fab")
		)
		(fp_line
			(start 0.8001 -1.050036)
			(end 0.8001 1.050036)
			(stroke
				(width 0.1)
				(type default)
			)
			(layer "F.Fab")
		)
		(fp_line
			(start -0.8001 1.050036)
			(end -0.8001 -1.050036)
			(stroke
				(width 0.1)
				(type default)
			)
			(layer "F.Fab")
		)
		(fp_line
			(start -0.8001 -1.050036)
			(end 0.8001 -1.050036)
			(stroke
				(width 0.1)
				(type default)
			)
			(layer "F.Fab")
		)
		(fp_poly
			(pts
				(xy -2.458974 -0.508) (xy -2.458974 0.508) (xy -1.442974 0)
			)
			(stroke
				(width 0)
				(type default)
			)
			(fill yes)
			(layer "F.Fab")
		)
		(pad "1_2" smd circle
			(at -0.374904 0 270)
			(size 0 0)
			(layers "F.Cu" "F.Mask" "F.Paste")
			(net "P12V_AUX")
		)
		(pad "3" smd rect
			(at -0.499872 0.999998 180)
			(size 0.254 0.7112)
			(layers "F.Cu" "F.Mask" "F.Paste")
			(net "GND")
		)
		(pad "4" smd rect
			(at 0 0.999998 180)
			(size 0.254 0.7112)
			(layers "F.Cu" "F.Mask" "F.Paste")
			(net "P12V_SSD15_CO_ILIMIT")
		)
		(pad "5" smd rect
			(at 0.499872 0.999998 180)
			(size 0.254 0.7112)
			(layers "F.Cu" "F.Mask" "F.Paste")
			(net "P12V_SSD15_CO_MODE")
		)
		(pad "6_7" smd circle
			(at 0.374904 0 90)
			(size 0 0)
			(layers "F.Cu" "F.Mask" "F.Paste")
			(net "P12V_SSD15_R")
		)
		(pad "8" smd rect
			(at 0.499872 -0.999998 180)
			(size 0.254 0.7112)
			(layers "F.Cu" "F.Mask" "F.Paste")
			(net "P12V_SSD15_CO_GATE")
		)
		(pad "9" smd rect
			(at 0 -0.999998 180)
			(size 0.254 0.7112)
			(layers "F.Cu" "F.Mask" "F.Paste")
			(net "P12V_SSD15_CO_EN")
		)
		(pad "10" smd rect
			(at -0.499872 -0.999998 180)
			(size 0.254 0.7112)
			(layers "F.Cu" "F.Mask" "F.Paste")
			(net "P12V_SSD15_CO_DV_DT")
		)
	)
	(footprint ""
		(layer "F.Cu")
		(at 89.602818 -302.666146 180)
		(property "Reference" "R6659"
			(at 0 0 180)
			(layer "F.SilkS")
			(hide yes)
			(effects
				(font
					(size 1.27 1.27)
				)
			)
		)
		(property "Value" ""
			(at 0 0 180)
			(layer "F.Fab")
			(effects
				(font
					(size 1.27 1.27)
				)
			)
		)
		(duplicate_pad_numbers_are_jumpers no)
		(fp_line
			(start 0.7874 0.4064)
			(end -0.7874 0.4064)
			(stroke
				(width 0.1524)
				(type default)
			)
			(layer "F.SilkS")
		)
		(fp_line
			(start 0.7874 -0.4064)
			(end 0.7874 0.4064)
			(stroke
				(width 0.1524)
				(type default)
			)
			(layer "F.SilkS")
		)
		(fp_line
			(start -0.7874 0.4064)
			(end -0.7874 -0.4064)
			(stroke
				(width 0.1524)
				(type default)
			)
			(layer "F.SilkS")
		)
		(fp_line
			(start -0.7874 -0.4064)
			(end 0.7874 -0.4064)
			(stroke
				(width 0.1524)
				(type default)
			)
			(layer "F.SilkS")
		)
		(fp_line
			(start 0.67945 0.3048)
			(end 0.120396 0.3048)
			(stroke
				(width 0.1)
				(type default)
			)
			(layer "F.Fab")
		)
		(fp_line
			(start 0.67945 -0.3048)
			(end 0.67945 0.3048)
			(stroke
				(width 0.1)
				(type default)
			)
			(layer "F.Fab")
		)
		(fp_line
			(start 0.12065 -0.2794)
			(end 0.12065 -0.3048)
			(stroke
				(width 0.1)
				(type default)
			)
			(layer "F.Fab")
		)
		(fp_line
			(start 0.12065 -0.3048)
			(end 0.67945 -0.3048)
			(stroke
				(width 0.1)
				(type default)
			)
			(layer "F.Fab")
		)
		(fp_line
			(start 0.120396 0.3048)
			(end 0.120396 0.2794)
			(stroke
				(width 0.1)
				(type default)
			)
			(layer "F.Fab")
		)
		(fp_line
			(start 0.120396 0.2794)
			(end -0.12065 0.2794)
			(stroke
				(width 0.1)
				(type default)
			)
			(layer "F.Fab")
		)
		(fp_line
			(start -0.12065 0.3048)
			(end -0.67945 0.3048)
			(stroke
				(width 0.1)
				(type default)
			)
			(layer "F.Fab")
		)
		(fp_line
			(start -0.12065 0.2794)
			(end -0.12065 0.3048)
			(stroke
				(width 0.1)
				(type default)
			)
			(layer "F.Fab")
		)
		(fp_line
			(start -0.12065 -0.2794)
			(end 0.12065 -0.2794)
			(stroke
				(width 0.1)
				(type default)
			)
			(layer "F.Fab")
		)
		(fp_line
			(start -0.12065 -0.305054)
			(end -0.12065 -0.2794)
			(stroke
				(width 0.1)
				(type default)
			)
			(layer "F.Fab")
		)
		(fp_line
			(start -0.67945 0.3048)
			(end -0.67945 -0.305054)
			(stroke
				(width 0.1)
				(type default)
			)
			(layer "F.Fab")
		)
		(fp_line
			(start -0.67945 -0.305054)
			(end -0.12065 -0.305054)
			(stroke
				(width 0.1)
				(type default)
			)
			(layer "F.Fab")
		)
		(pad "1" smd circle
			(at -0.40005 0 180)
			(size 0 0)
			(layers "F.Cu" "F.Mask" "F.Paste")
			(net "SMB_PEX0_SLAVE1_SDA")
		)
		(pad "2" smd circle
			(at 0.40005 0 180)
			(size 0 0)
			(layers "F.Cu" "F.Mask" "F.Paste")
			(net "SMB_PEX0_R_SDA")
		)
	)
	(footprint ""
		(layer "F.Cu")
		(at 263.594088 -29.507688 -90)
		(property "Reference" "PC943"
			(at 0 0 270)
			(layer "F.SilkS")
			(hide yes)
			(effects
				(font
					(size 1.27 1.27)
				)
			)
		)
		(property "Value" ""
			(at 0 0 270)
			(layer "F.Fab")
			(effects
				(font
					(size 1.27 1.27)
				)
			)
		)
		(duplicate_pad_numbers_are_jumpers no)
		(fp_line
			(start -1.524 0.762)
			(end -1.524 -0.762)
			(stroke
				(width 0.1524)
				(type default)
			)
			(layer "F.SilkS")
		)
		(fp_line
			(start 1.524 0.762)
			(end -1.524 0.762)
			(stroke
				(width 0.1524)
				(type default)
			)
			(layer "F.SilkS")
		)
		(fp_line
			(start -1.524 -0.762)
			(end 1.524 -0.762)
			(stroke
				(width 0.1524)
				(type default)
			)
			(layer "F.SilkS")
		)
		(fp_line
			(start 1.524 -0.762)
			(end 1.524 0.762)
			(stroke
				(width 0.1524)
				(type default)
			)
			(layer "F.SilkS")
		)
		(fp_line
			(start -1.1049 0.724916)
			(end 1.1049 0.724916)
			(stroke
				(width 0.1)
				(type default)
			)
			(layer "F.Fab")
		)
		(fp_line
			(start 1.1049 0.724916)
			(end 1.1049 -0.724916)
			(stroke
				(width 0.1)
				(type default)
			)
			(layer "F.Fab")
		)
		(fp_line
			(start -1.1049 -0.724916)
			(end -1.1049 0.724916)
			(stroke
				(width 0.1)
				(type default)
			)
			(layer "F.Fab")
		)
		(fp_line
			(start 1.1049 -0.724916)
			(end -1.1049 -0.724916)
			(stroke
				(width 0.1)
				(type default)
			)
			(layer "F.Fab")
		)
		(pad "1" smd rect
			(at -0.889 0 90)
			(size 1.016 1.27)
			(layers "F.Cu" "F.Mask" "F.Paste")
			(net "P3V3_SSD9")
		)
		(pad "2" smd rect
			(at 0.889 0 90)
			(size 1.016 1.27)
			(layers "F.Cu" "F.Mask" "F.Paste")
			(net "GND")
		)
	)
)
